# T6G (Grand Teton) — schematic netlist excerpt (pin names and nets, part order shuffled) for the footprints in the layout excerpt that follows; sources: Cadence DE-HDL packaged netlist, KiCad conversion of 04192023_DAF0TMB3IC0_F0TG_MB_C_brd_V02_OCP.brd

PC194  Q_CAP  3300PF 50V 10% X7R  pkg 0402  page 207 : A = VSENSE_PVDD11_S3_P0_R ; B = VSENSE_VSS_SENSE_C_P0
R2900  Q_RES  2K 1% CHIP  pkg 0402LF  page 257 : A = MAX11617_VREF ; B = MAX11617_VREF_R

(kicad_pcb
	(version 20260206)
	(generator "pcbnew")
	(generator_version "10.0")
	(general
		(thickness 1.6)
		(legacy_teardrops no)
	)
	(paper "A4")
	(title_block
		(title "04192023_DAF0TMB3IC0_F0TG_MB_C_brd_V02_OCP.brd")
		(comment 1 "Grand Teton / footprints 3094-3095 of 8354")
	)
	(layers
		(0 "F.Cu" signal "TOP")
		(4 "In1.Cu" signal "GND")
		(6 "In2.Cu" signal "IN1")
		(8 "In3.Cu" signal "GND1")
		(10 "In4.Cu" signal "IN2")
		(12 "In5.Cu" signal "GND2")
		(14 "In6.Cu" signal "IN3")
		(16 "In7.Cu" signal "GND3")
		(18 "In8.Cu" signal "VCC")
		(20 "In9.Cu" signal "VCC1")
		(22 "In10.Cu" signal "GND4")
		(24 "In11.Cu" signal "IN4")
		(26 "In12.Cu" signal "GND5")
		(28 "In13.Cu" signal "IN5")
		(30 "In14.Cu" signal "GND6")
		(32 "In15.Cu" signal "IN6")
		(34 "In16.Cu" signal "GND7")
		(2 "B.Cu" signal "BOTTOM")
		(9 "F.Adhes" user "F.Adhesive")
		(11 "B.Adhes" user "B.Adhesive")
		(13 "F.Paste" user "Package Geometry/Pastemask Top")
		(15 "B.Paste" user "Package Geometry/Pastemask Bottom")
		(5 "F.SilkS" user "Ref Des/Silkscreen Top")
		(7 "B.SilkS" user "Ref Des/Silkscreen Bottom")
		(1 "F.Mask" user "Board Geometry/Soldermask Top")
		(3 "B.Mask" user "Board Geometry/Soldermask Bottom")
		(17 "Dwgs.User" user "User.Drawings")
		(19 "Cmts.User" user "User.Comments")
		(21 "Eco1.User" user "User.Eco1")
		(23 "Eco2.User" user "User.Eco2")
		(25 "Edge.Cuts" user "Board Geometry/Outline")
		(27 "Margin" user)
		(31 "F.CrtYd" user "Package Geometry/Place Bound Top")
		(29 "B.CrtYd" user "Package Geometry/Place Bound Bottom")
		(35 "F.Fab" user "Ref Des/Assembly Top")
		(33 "B.Fab" user "Ref Des/Assembly Bottom")
	)
	(footprint ""
		(layer "F.Cu")
		(at 315.771022 -36.890706)
		(property "Reference" "R2900"
			(at 0 0 0)
			(layer "F.SilkS")
			(hide yes)
			(effects
				(font
					(size 1.27 1.27)
				)
			)
		)
		(property "Value" ""
			(at 0 0 0)
			(layer "F.Fab")
			(effects
				(font
					(size 1.27 1.27)
				)
			)
		)
		(duplicate_pad_numbers_are_jumpers no)
		(fp_line
			(start -0.7874 -0.4064)
			(end 0.7874 -0.4064)
			(stroke
				(width 0.1524)
				(type default)
			)
			(layer "F.SilkS")
		)
		(fp_line
			(start -0.7874 0.4064)
			(end -0.7874 -0.4064)
			(stroke
				(width 0.1524)
				(type default)
			)
			(layer "F.SilkS")
		)
		(fp_line
			(start 0.7874 -0.4064)
			(end 0.7874 0.4064)
			(stroke
				(width 0.1524)
				(type default)
			)
			(layer "F.SilkS")
		)
		(fp_line
			(start 0.7874 0.4064)
			(end -0.7874 0.4064)
			(stroke
				(width 0.1524)
				(type default)
			)
			(layer "F.SilkS")
		)
		(fp_line
			(start -0.67945 -0.305054)
			(end -0.12065 -0.305054)
			(stroke
				(width 0.1)
				(type default)
			)
			(layer "F.Fab")
		)
		(fp_line
			(start -0.67945 0.3048)
			(end -0.67945 -0.305054)
			(stroke
				(width 0.1)
				(type default)
			)
			(layer "F.Fab")
		)
		(fp_line
			(start -0.12065 -0.305054)
			(end -0.12065 -0.2794)
			(stroke
				(width 0.1)
				(type default)
			)
			(layer "F.Fab")
		)
		(fp_line
			(start -0.12065 -0.2794)
			(end 0.12065 -0.2794)
			(stroke
				(width 0.1)
				(type default)
			)
			(layer "F.Fab")
		)
		(fp_line
			(start -0.12065 0.2794)
			(end -0.12065 0.3048)
			(stroke
				(width 0.1)
				(type default)
			)
			(layer "F.Fab")
		)
		(fp_line
			(start -0.12065 0.3048)
			(end -0.67945 0.3048)
			(stroke
				(width 0.1)
				(type default)
			)
			(layer "F.Fab")
		)
		(fp_line
			(start 0.120396 0.2794)
			(end -0.12065 0.2794)
			(stroke
				(width 0.1)
				(type default)
			)
			(layer "F.Fab")
		)
		(fp_line
			(start 0.120396 0.3048)
			(end 0.120396 0.2794)
			(stroke
				(width 0.1)
				(type default)
			)
			(layer "F.Fab")
		)
		(fp_line
			(start 0.12065 -0.3048)
			(end 0.67945 -0.3048)
			(stroke
				(width 0.1)
				(type default)
			)
			(layer "F.Fab")
		)
		(fp_line
			(start 0.12065 -0.2794)
			(end 0.12065 -0.3048)
			(stroke
				(width 0.1)
				(type default)
			)
			(layer "F.Fab")
		)
		(fp_line
			(start 0.67945 -0.3048)
			(end 0.67945 0.3048)
			(stroke
				(width 0.1)
				(type default)
			)
			(layer "F.Fab")
		)
		(fp_line
			(start 0.67945 0.3048)
			(end 0.120396 0.3048)
			(stroke
				(width 0.1)
				(type default)
			)
			(layer "F.Fab")
		)
		(pad "1" smd circle
			(at -0.40005 0)
			(size 0 0)
			(layers "F.Cu" "F.Mask" "F.Paste")
			(net "MAX11617_VREF")
		)
		(pad "2" smd circle
			(at 0.40005 0)
			(size 0 0)
			(layers "F.Cu" "F.Mask" "F.Paste")
			(net "MAX11617_VREF_R")
		)
	)
	(footprint ""
		(layer "F.Cu")
		(at 416.43046 -358.241092)
		(property "Reference" "PC194"
			(at 0 0 0)
			(layer "F.SilkS")
			(hide yes)
			(effects
				(font
					(size 1.27 1.27)
				)
			)
		)
		(property "Value" ""
			(at 0 0 0)
			(layer "F.Fab")
			(effects
				(font
					(size 1.27 1.27)
				)
			)
		)
		(duplicate_pad_numbers_are_jumpers no)
		(fp_line
			(start -0.7874 -0.4064)
			(end 0.7874 -0.4064)
			(stroke
				(width 0.1524)
				(type default)
			)
			(layer "F.SilkS")
		)
		(fp_line
			(start -0.7874 0.4064)
			(end -0.7874 -0.4064)
			(stroke
				(width 0.1524)
				(type default)
			)
			(layer "F.SilkS")
		)
		(fp_line
			(start 0.7874 -0.4064)
			(end 0.7874 0.4064)
			(stroke
				(width 0.1524)
				(type default)
			)
			(layer "F.SilkS")
		)
		(fp_line
			(start 0.7874 0.4064)
			(end -0.7874 0.4064)
			(stroke
				(width 0.1524)
				(type default)
			)
			(layer "F.SilkS")
		)
		(fp_line
			(start -0.67945 -0.305054)
			(end -0.12065 -0.305054)
			(stroke
				(width 0.1)
				(type default)
			)
			(layer "F.Fab")
		)
		(fp_line
			(start -0.67945 0.3048)
			(end -0.67945 -0.305054)
			(stroke
				(width 0.1)
				(type default)
			)
			(layer "F.Fab")
		)
		(fp_line
			(start -0.12065 -0.305054)
			(end -0.12065 -0.2794)
			(stroke
				(width 0.1)
				(type default)
			)
			(layer "F.Fab")
		)
		(fp_line
			(start -0.12065 -0.2794)
			(end 0.12065 -0.2794)
			(stroke
				(width 0.1)
				(type default)
			)
			(layer "F.Fab")
		)
		(fp_line
			(start -0.12065 0.2794)
			(end -0.12065 0.3048)
			(stroke
				(width 0.1)
				(type default)
			)
			(layer "F.Fab")
		)
		(fp_line
			(start -0.12065 0.3048)
			(end -0.67945 0.3048)
			(stroke
				(width 0.1)
				(type default)
			)
			(layer "F.Fab")
		)
		(fp_line
			(start 0.120396 0.2794)
			(end -0.12065 0.2794)
			(stroke
				(width 0.1)
				(type default)
			)
			(layer "F.Fab")
		)
		(fp_line
			(start 0.120396 0.3048)
			(end 0.120396 0.2794)
			(stroke
				(width 0.1)
				(type default)
			)
			(layer "F.Fab")
		)
		(fp_line
			(start 0.12065 -0.3048)
			(end 0.67945 -0.3048)
			(stroke
				(width 0.1)
				(type default)
			)
			(layer "F.Fab")
		)
		(fp_line
			(start 0.12065 -0.2794)
			(end 0.12065 -0.3048)
			(stroke
				(width 0.1)
				(type default)
			)
			(layer "F.Fab")
		)
		(fp_line
			(start 0.67945 -0.3048)
			(end 0.67945 0.3048)
			(stroke
				(width 0.1)
				(type default)
			)
			(layer "F.Fab")
		)
		(fp_line
			(start 0.67945 0.3048)
			(end 0.120396 0.3048)
			(stroke
				(width 0.1)
				(type default)
			)
			(layer "F.Fab")
		)
		(pad "1" smd circle
			(at -0.40005 0)
			(size 0 0)
			(layers "F.Cu" "F.Mask" "F.Paste")
			(net "VSENSE_PVDD11_S3_P0_R")
		)
		(pad "2" smd circle
			(at 0.40005 0)
			(size 0 0)
			(layers "F.Cu" "F.Mask" "F.Paste")
			(net "VSENSE_VSS_SENSE_C_P0")
		)
	)
)
